# S9S_MB_2U (Grand Teton) — schematic netlist excerpt (pin names and nets, part order shuffled) for the footprints in the layout excerpt that follows; sources: Cadence DE-HDL packaged netlist, KiCad conversion of 03242023_DA0F0TMBIJ0_F0T_Motherboard_J_brd_V01_OCP.brd

R5236  Q_RES  0 5% CHIP  pkg 0402LF  page 152 : A = USB2_HUB_BUF_SWB_R_DN ; B = USB2_HUB_BUF_SWB_DN
L4  Q_INDUCTOR  BLM18SG331TN1D/1.5A IND  pkg SMLF  page 206 : \1\ = P3V3 ; \2\ = P3V3_DB2000_FB_VDD

(kicad_pcb
	(version 20260206)
	(generator "pcbnew")
	(generator_version "10.0")
	(general
		(thickness 1.6)
		(legacy_teardrops no)
	)
	(paper "A4")
	(title_block
		(title "03242023_DA0F0TMBIJ0_F0T_Motherboard_J_brd_V01_OCP.brd")
		(comment 1 "Grand Teton / footprints 5425-5426 of 6105")
	)
	(layers
		(0 "F.Cu" signal "TOP")
		(4 "In1.Cu" signal "GND")
		(6 "In2.Cu" signal "IN1")
		(8 "In3.Cu" signal "GND1")
		(10 "In4.Cu" signal "IN2")
		(12 "In5.Cu" signal "GND2")
		(14 "In6.Cu" signal "IN3")
		(16 "In7.Cu" signal "GND3")
		(18 "In8.Cu" signal "VCC")
		(20 "In9.Cu" signal "VCC1")
		(22 "In10.Cu" signal "GND4")
		(24 "In11.Cu" signal "IN4")
		(26 "In12.Cu" signal "GND5")
		(28 "In13.Cu" signal "IN5")
		(30 "In14.Cu" signal "GND6")
		(32 "In15.Cu" signal "IN6")
		(34 "In16.Cu" signal "GND7")
		(2 "B.Cu" signal "BOTTOM")
		(9 "F.Adhes" user "F.Adhesive")
		(11 "B.Adhes" user "B.Adhesive")
		(13 "F.Paste" user "Package Geometry/Pastemask Top")
		(15 "B.Paste" user "Package Geometry/Pastemask Bottom")
		(5 "F.SilkS" user "Ref Des/Silkscreen Top")
		(7 "B.SilkS" user "Ref Des/Silkscreen Bottom")
		(1 "F.Mask" user "Board Geometry/Soldermask Top")
		(3 "B.Mask" user "Board Geometry/Soldermask Bottom")
		(17 "Dwgs.User" user "User.Drawings")
		(19 "Cmts.User" user "User.Comments")
		(21 "Eco1.User" user "User.Eco1")
		(23 "Eco2.User" user "User.Eco2")
		(25 "Edge.Cuts" user "Board Geometry/Outline")
		(27 "Margin" user)
		(31 "F.CrtYd" user "Package Geometry/Place Bound Top")
		(29 "B.CrtYd" user "Package Geometry/Place Bound Bottom")
		(35 "F.Fab" user "Ref Des/Assembly Top")
		(33 "B.Fab" user "Ref Des/Assembly Bottom")
	)
	(footprint ""
		(layer "B.Cu")
		(at 36.488624 -407.077164 180)
		(property "Reference" "R5236"
			(at 0 0 0)
			(layer "B.SilkS")
			(hide yes)
			(effects
				(font
					(size 1.27 1.27)
				)
				(justify mirror)
			)
		)
		(property "Value" ""
			(at 0 0 0)
			(layer "B.Fab")
			(effects
				(font
					(size 1.27 1.27)
				)
				(justify mirror)
			)
		)
		(duplicate_pad_numbers_are_jumpers no)
		(fp_line
			(start 0.7874 0.4064)
			(end 0.7874 -0.028956)
			(stroke
				(width 0.1524)
				(type default)
			)
			(layer "B.SilkS")
		)
		(fp_line
			(start 0.529844 -0.4064)
			(end -0.407416 -0.4064)
			(stroke
				(width 0.1524)
				(type default)
			)
			(layer "B.SilkS")
		)
		(fp_line
			(start -0.7874 0.4064)
			(end 0.7874 0.4064)
			(stroke
				(width 0.1524)
				(type default)
			)
			(layer "B.SilkS")
		)
		(fp_line
			(start -0.7874 -0.105156)
			(end -0.7874 0.4064)
			(stroke
				(width 0.1524)
				(type default)
			)
			(layer "B.SilkS")
		)
		(fp_line
			(start 0.67945 0.3048)
			(end 0.67945 -0.305054)
			(stroke
				(width 0.1)
				(type default)
			)
			(layer "B.Fab")
		)
		(fp_line
			(start 0.67945 -0.305054)
			(end 0.12065 -0.305054)
			(stroke
				(width 0.1)
				(type default)
			)
			(layer "B.Fab")
		)
		(fp_line
			(start 0.12065 0.3048)
			(end 0.67945 0.3048)
			(stroke
				(width 0.1)
				(type default)
			)
			(layer "B.Fab")
		)
		(fp_line
			(start 0.12065 0.2794)
			(end 0.12065 0.3048)
			(stroke
				(width 0.1)
				(type default)
			)
			(layer "B.Fab")
		)
		(fp_line
			(start 0.12065 -0.2794)
			(end -0.12065 -0.2794)
			(stroke
				(width 0.1)
				(type default)
			)
			(layer "B.Fab")
		)
		(fp_line
			(start 0.12065 -0.305054)
			(end 0.12065 -0.2794)
			(stroke
				(width 0.1)
				(type default)
			)
			(layer "B.Fab")
		)
		(fp_line
			(start -0.120396 0.3048)
			(end -0.120396 0.2794)
			(stroke
				(width 0.1)
				(type default)
			)
			(layer "B.Fab")
		)
		(fp_line
			(start -0.120396 0.2794)
			(end 0.12065 0.2794)
			(stroke
				(width 0.1)
				(type default)
			)
			(layer "B.Fab")
		)
		(fp_line
			(start -0.12065 -0.2794)
			(end -0.12065 -0.3048)
			(stroke
				(width 0.1)
				(type default)
			)
			(layer "B.Fab")
		)
		(fp_line
			(start -0.12065 -0.3048)
			(end -0.67945 -0.3048)
			(stroke
				(width 0.1)
				(type default)
			)
			(layer "B.Fab")
		)
		(fp_line
			(start -0.67945 0.3048)
			(end -0.120396 0.3048)
			(stroke
				(width 0.1)
				(type default)
			)
			(layer "B.Fab")
		)
		(fp_line
			(start -0.67945 -0.3048)
			(end -0.67945 0.3048)
			(stroke
				(width 0.1)
				(type default)
			)
			(layer "B.Fab")
		)
		(pad "1" smd circle
			(at 0.40005 0)
			(size 0 0)
			(layers "B.Cu" "B.Mask" "B.Paste")
			(net "USB2_HUB_BUF_SWB_R_DN")
		)
		(pad "2" smd circle
			(at -0.40005 0)
			(size 0 0)
			(layers "B.Cu" "B.Mask" "B.Paste")
			(net "USB2_HUB_BUF_SWB_DN")
		)
	)
	(footprint ""
		(layer "B.Cu")
		(at 232.003854 -121.616216 -90)
		(property "Reference" "L4"
			(at 0 0 90)
			(layer "B.SilkS")
			(hide yes)
			(effects
				(font
					(size 1.27 1.27)
				)
				(justify mirror)
			)
		)
		(property "Value" ""
			(at 0 0 90)
			(layer "B.Fab")
			(effects
				(font
					(size 1.27 1.27)
				)
				(justify mirror)
			)
		)
		(duplicate_pad_numbers_are_jumpers no)
		(fp_line
			(start -1.27 0.5842)
			(end 1.27 0.5842)
			(stroke
				(width 0.1524)
				(type default)
			)
			(layer "B.SilkS")
		)
		(fp_line
			(start -1.27 0.5842)
			(end -1.27 -0.5842)
			(stroke
				(width 0.1524)
				(type default)
			)
			(layer "B.SilkS")
		)
		(fp_line
			(start -0.127 0.5842)
			(end -0.127 -0.5842)
			(stroke
				(width 0.1524)
				(type default)
			)
			(layer "B.SilkS")
		)
		(fp_line
			(start 0.127 0.5842)
			(end 0.127 -0.5842)
			(stroke
				(width 0.1524)
				(type default)
			)
			(layer "B.SilkS")
		)
		(fp_line
			(start 1.27 0.5842)
			(end 1.27 -0.5842)
			(stroke
				(width 0.1524)
				(type default)
			)
			(layer "B.SilkS")
		)
		(fp_line
			(start 1.27 -0.5588)
			(end 1.27 -0.5842)
			(stroke
				(width 0.1524)
				(type default)
			)
			(layer "B.SilkS")
		)
		(fp_line
			(start 1.27 -0.5842)
			(end -1.27 -0.5842)
			(stroke
				(width 0.1524)
				(type default)
			)
			(layer "B.SilkS")
		)
		(fp_line
			(start -0.9144 0.508)
			(end 0.9144 0.508)
			(stroke
				(width 0.1)
				(type default)
			)
			(layer "B.Fab")
		)
		(fp_line
			(start 0.9144 0.508)
			(end 0.9144 0.406654)
			(stroke
				(width 0.1)
				(type default)
			)
			(layer "B.Fab")
		)
		(fp_line
			(start 0.9144 0.406654)
			(end 1.194308 0.406654)
			(stroke
				(width 0.1)
				(type default)
			)
			(layer "B.Fab")
		)
		(fp_line
			(start 1.194308 0.406654)
			(end 1.194308 -0.406654)
			(stroke
				(width 0.1)
				(type default)
			)
			(layer "B.Fab")
		)
		(fp_line
			(start -1.1938 0.4064)
			(end -0.9144 0.4064)
			(stroke
				(width 0.1)
				(type default)
			)
			(layer "B.Fab")
		)
		(fp_line
			(start -0.9144 0.4064)
			(end -0.9144 0.508)
			(stroke
				(width 0.1)
				(type default)
			)
			(layer "B.Fab")
		)
		(fp_line
			(start -1.1938 -0.406654)
			(end -1.1938 0.4064)
			(stroke
				(width 0.1)
				(type default)
			)
			(layer "B.Fab")
		)
		(fp_line
			(start -0.9144 -0.406654)
			(end -1.1938 -0.406654)
			(stroke
				(width 0.1)
				(type default)
			)
			(layer "B.Fab")
		)
		(fp_line
			(start 0.9144 -0.406654)
			(end 0.9144 -0.508)
			(stroke
				(width 0.1)
				(type default)
			)
			(layer "B.Fab")
		)
		(fp_line
			(start 1.194308 -0.406654)
			(end 0.9144 -0.406654)
			(stroke
				(width 0.1)
				(type default)
			)
			(layer "B.Fab")
		)
		(fp_line
			(start -0.9144 -0.508)
			(end -0.9144 -0.406654)
			(stroke
				(width 0.1)
				(type default)
			)
			(layer "B.Fab")
		)
		(fp_line
			(start 0.9144 -0.508)
			(end -0.9144 -0.508)
			(stroke
				(width 0.1)
				(type default)
			)
			(layer "B.Fab")
		)
		(pad "1" smd rect
			(at 0.7366 0 180)
			(size 0.7112 0.8128)
			(layers "B.Cu" "B.Mask" "B.Paste")
			(net "P3V3")
		)
		(pad "2" smd rect
			(at -0.7366 0 180)
			(size 0.7112 0.8128)
			(layers "B.Cu" "B.Mask" "B.Paste")
			(net "P3V3_DB2000_FB_VDD")
		)
	)
)
